(kicad_pcb
	(version 20260206)
	(generator "pcbnew")
	(generator_version "10.0")
	(general
		(thickness 1.6)
		(legacy_teardrops no)
	)
	(paper "A4")
	(title_block
		(title "04192023_DAF0TMB3IC0_F0TG_MB_C_brd_V02_OCP.brd")
		(comment 1 "Grand Teton / footprints 3139-3146 of 8354")
	)
	(layers
		(0 "F.Cu" signal "TOP")
		(4 "In1.Cu" signal "GND")
		(6 "In2.Cu" signal "IN1")
		(8 "In3.Cu" signal "GND1")
		(10 "In4.Cu" signal "IN2")
		(12 "In5.Cu" signal "GND2")
		(14 "In6.Cu" signal "IN3")
		(16 "In7.Cu" signal "GND3")
		(18 "In8.Cu" signal "VCC")
		(20 "In9.Cu" signal "VCC1")
		(22 "In10.Cu" signal "GND4")
		(24 "In11.Cu" signal "IN4")
		(26 "In12.Cu" signal "GND5")
		(28 "In13.Cu" signal "IN5")
		(30 "In14.Cu" signal "GND6")
		(32 "In15.Cu" signal "IN6")
		(34 "In16.Cu" signal "GND7")
		(2 "B.Cu" signal "BOTTOM")
		(9 "F.Adhes" user "F.Adhesive")
		(11 "B.Adhes" user "B.Adhesive")
		(13 "F.Paste" user "Package Geometry/Pastemask Top")
		(15 "B.Paste" user "Package Geometry/Pastemask Bottom")
		(5 "F.SilkS" user "Ref Des/Silkscreen Top")
		(7 "B.SilkS" user "Ref Des/Silkscreen Bottom")
		(1 "F.Mask" user "Board Geometry/Soldermask Top")
		(3 "B.Mask" user "Board Geometry/Soldermask Bottom")
		(17 "Dwgs.User" user "User.Drawings")
		(19 "Cmts.User" user "User.Comments")
		(21 "Eco1.User" user "User.Eco1")
		(23 "Eco2.User" user "User.Eco2")
		(25 "Edge.Cuts" user "Board Geometry/Outline")
		(27 "Margin" user)
		(31 "F.CrtYd" user "Package Geometry/Place Bound Top")
		(29 "B.CrtYd" user "Package Geometry/Place Bound Bottom")
		(35 "F.Fab" user "Ref Des/Assembly Top")
		(33 "B.Fab" user "Ref Des/Assembly Bottom")
	)
	(footprint ""
		(layer "F.Cu")
		(at 178.689 -407.543 180)
		(property "Reference" "R1117"
			(at 0 0 180)
			(layer "F.SilkS")
			(hide yes)
			(effects
				(font
					(size 1.27 1.27)
				)
			)
		)
		(property "Value" ""
			(at 0 0 180)
			(layer "F.Fab")
			(effects
				(font
					(size 1.27 1.27)
				)
			)
		)
		(duplicate_pad_numbers_are_jumpers no)
		(fp_line
			(start 0.7874 0.4064)
			(end -0.7874 0.4064)
			(stroke
				(width 0.1524)
				(type default)
			)
			(layer "F.SilkS")
		)
		(fp_line
			(start 0.7874 -0.4064)
			(end 0.7874 0.4064)
			(stroke
				(width 0.1524)
				(type default)
			)
			(layer "F.SilkS")
		)
		(fp_line
			(start -0.7874 0.4064)
			(end -0.7874 -0.4064)
			(stroke
				(width 0.1524)
				(type default)
			)
			(layer "F.SilkS")
		)
		(fp_line
			(start -0.7874 -0.4064)
			(end 0.7874 -0.4064)
			(stroke
				(width 0.1524)
				(type default)
			)
			(layer "F.SilkS")
		)
		(fp_line
			(start 0.67945 0.3048)
			(end 0.120396 0.3048)
			(stroke
				(width 0.1)
				(type default)
			)
			(layer "F.Fab")
		)
		(fp_line
			(start 0.67945 -0.3048)
			(end 0.67945 0.3048)
			(stroke
				(width 0.1)
				(type default)
			)
			(layer "F.Fab")
		)
		(fp_line
			(start 0.12065 -0.2794)
			(end 0.12065 -0.3048)
			(stroke
				(width 0.1)
				(type default)
			)
			(layer "F.Fab")
		)
		(fp_line
			(start 0.12065 -0.3048)
			(end 0.67945 -0.3048)
			(stroke
				(width 0.1)
				(type default)
			)
			(layer "F.Fab")
		)
		(fp_line
			(start 0.120396 0.3048)
			(end 0.120396 0.2794)
			(stroke
				(width 0.1)
				(type default)
			)
			(layer "F.Fab")
		)
		(fp_line
			(start 0.120396 0.2794)
			(end -0.12065 0.2794)
			(stroke
				(width 0.1)
				(type default)
			)
			(layer "F.Fab")
		)
		(fp_line
			(start -0.12065 0.3048)
			(end -0.67945 0.3048)
			(stroke
				(width 0.1)
				(type default)
			)
			(layer "F.Fab")
		)
		(fp_line
			(start -0.12065 0.2794)
			(end -0.12065 0.3048)
			(stroke
				(width 0.1)
				(type default)
			)
			(layer "F.Fab")
		)
		(fp_line
			(start -0.12065 -0.2794)
			(end 0.12065 -0.2794)
			(stroke
				(width 0.1)
				(type default)
			)
			(layer "F.Fab")
		)
		(fp_line
			(start -0.12065 -0.305054)
			(end -0.12065 -0.2794)
			(stroke
				(width 0.1)
				(type default)
			)
			(layer "F.Fab")
		)
		(fp_line
			(start -0.67945 0.3048)
			(end -0.67945 -0.305054)
			(stroke
				(width 0.1)
				(type default)
			)
			(layer "F.Fab")
		)
		(fp_line
			(start -0.67945 -0.305054)
			(end -0.12065 -0.305054)
			(stroke
				(width 0.1)
				(type default)
			)
			(layer "F.Fab")
		)
		(pad "1" smd circle
			(at -0.40005 0 180)
			(size 0 0)
			(layers "F.Cu" "F.Mask" "F.Paste")
			(net "MB0_P12V_STBY_PWRGD")
		)
		(pad "2" smd circle
			(at 0.40005 0 180)
			(size 0 0)
			(layers "F.Cu" "F.Mask" "F.Paste")
			(net "AGND_HSC")
		)
	)
	(footprint ""
		(layer "F.Cu")
		(at 34.665158 -170.50766)
		(property "Reference" "R1293"
			(at 0 0 0)
			(layer "F.SilkS")
			(hide yes)
			(effects
				(font
					(size 1.27 1.27)
				)
			)
		)
		(property "Value" ""
			(at 0 0 0)
			(layer "F.Fab")
			(effects
				(font
					(size 1.27 1.27)
				)
			)
		)
		(duplicate_pad_numbers_are_jumpers no)
		(fp_line
			(start -0.7874 -0.4064)
			(end 0.7874 -0.4064)
			(stroke
				(width 0.1524)
				(type default)
			)
			(layer "F.SilkS")
		)
		(fp_line
			(start -0.7874 0.4064)
			(end -0.7874 -0.4064)
			(stroke
				(width 0.1524)
				(type default)
			)
			(layer "F.SilkS")
		)
		(fp_line
			(start 0.7874 -0.4064)
			(end 0.7874 0.4064)
			(stroke
				(width 0.1524)
				(type default)
			)
			(layer "F.SilkS")
		)
		(fp_line
			(start 0.7874 0.4064)
			(end -0.7874 0.4064)
			(stroke
				(width 0.1524)
				(type default)
			)
			(layer "F.SilkS")
		)
		(fp_line
			(start -0.67945 -0.305054)
			(end -0.12065 -0.305054)
			(stroke
				(width 0.1)
				(type default)
			)
			(layer "F.Fab")
		)
		(fp_line
			(start -0.67945 0.3048)
			(end -0.67945 -0.305054)
			(stroke
				(width 0.1)
				(type default)
			)
			(layer "F.Fab")
		)
		(fp_line
			(start -0.12065 -0.305054)
			(end -0.12065 -0.2794)
			(stroke
				(width 0.1)
				(type default)
			)
			(layer "F.Fab")
		)
		(fp_line
			(start -0.12065 -0.2794)
			(end 0.12065 -0.2794)
			(stroke
				(width 0.1)
				(type default)
			)
			(layer "F.Fab")
		)
		(fp_line
			(start -0.12065 0.2794)
			(end -0.12065 0.3048)
			(stroke
				(width 0.1)
				(type default)
			)
			(layer "F.Fab")
		)
		(fp_line
			(start -0.12065 0.3048)
			(end -0.67945 0.3048)
			(stroke
				(width 0.1)
				(type default)
			)
			(layer "F.Fab")
		)
		(fp_line
			(start 0.120396 0.2794)
			(end -0.12065 0.2794)
			(stroke
				(width 0.1)
				(type default)
			)
			(layer "F.Fab")
		)
		(fp_line
			(start 0.120396 0.3048)
			(end 0.120396 0.2794)
			(stroke
				(width 0.1)
				(type default)
			)
			(layer "F.Fab")
		)
		(fp_line
			(start 0.12065 -0.3048)
			(end 0.67945 -0.3048)
			(stroke
				(width 0.1)
				(type default)
			)
			(layer "F.Fab")
		)
		(fp_line
			(start 0.12065 -0.2794)
			(end 0.12065 -0.3048)
			(stroke
				(width 0.1)
				(type default)
			)
			(layer "F.Fab")
		)
		(fp_line
			(start 0.67945 -0.3048)
			(end 0.67945 0.3048)
			(stroke
				(width 0.1)
				(type default)
			)
			(layer "F.Fab")
		)
		(fp_line
			(start 0.67945 0.3048)
			(end 0.120396 0.3048)
			(stroke
				(width 0.1)
				(type default)
			)
			(layer "F.Fab")
		)
		(pad "1" smd rect
			(at -0.40005 0 180)
			(size 0.4572 0.508)
			(layers "F.Cu" "F.Mask" "F.Paste")
			(net "I3C_SPD_DDRAF_CPU1_SCL")
		)
		(pad "2" smd rect
			(at 0.40005 0 180)
			(size 0.4572 0.508)
			(layers "F.Cu" "F.Mask" "F.Paste")
			(net "I3C_SPD_DDRAF_CPU1_LVC1_SCL")
		)
	)
	(footprint ""
		(layer "F.Cu")
		(at 31.429706 19.444716 -90)
		(property "Reference" "U26_SRM"
			(at 0 0 270)
			(layer "F.SilkS")
			(hide yes)
			(effects
				(font
					(size 1.27 1.27)
				)
			)
		)
		(property "Value" ""
			(at 0 0 270)
			(layer "F.Fab")
			(effects
				(font
					(size 1.27 1.27)
				)
			)
		)
		(duplicate_pad_numbers_are_jumpers no)
		(pad "1" smd circle
			(at 0 0 270)
			(size 0.762 0.762)
			(layers "F.Cu" "F.Mask" "F.Paste")
			(net "Net_10786")
		)
	)
	(footprint ""
		(layer "F.Cu")
		(at 298.300902 -20.255992 -90)
		(property "Reference" "U167"
			(at -0.130556 1.749552 90)
			(unlocked yes)
			(layer "F.SilkS")
			(effects
				(font
					(size 0.7874 0.5842)
					(thickness 0.1524)
				)
				(justify left)
			)
		)
		(property "Value" ""
			(at 0 0 270)
			(layer "F.Fab")
			(effects
				(font
					(size 1.27 1.27)
				)
			)
		)
		(duplicate_pad_numbers_are_jumpers no)
		(fp_line
			(start -1.538478 1.150874)
			(end 1.538478 1.150874)
			(stroke
				(width 0.1524)
				(type default)
			)
			(layer "F.SilkS")
		)
		(fp_line
			(start 1.538478 1.150874)
			(end 1.538478 -1.150874)
			(stroke
				(width 0.1524)
				(type default)
			)
			(layer "F.SilkS")
		)
		(fp_line
			(start -1.538478 -1.150874)
			(end -1.538478 1.150874)
			(stroke
				(width 0.1524)
				(type default)
			)
			(layer "F.SilkS")
		)
		(fp_line
			(start 1.538478 -1.150874)
			(end -1.538478 -1.150874)
			(stroke
				(width 0.1524)
				(type default)
			)
			(layer "F.SilkS")
		)
		(fp_poly
			(pts
				(xy -1.378966 -1.298448) (xy -2.187194 -1.567942) (xy -1.648206 -2.106676)
			)
			(stroke
				(width 0)
				(type default)
			)
			(fill yes)
			(layer "F.SilkS")
		)
		(fp_line
			(start -0.674878 1.100074)
			(end 0.674878 1.100074)
			(stroke
				(width 0.1)
				(type default)
			)
			(layer "F.Fab")
		)
		(fp_line
			(start 0.674878 1.100074)
			(end 0.674878 -1.100074)
			(stroke
				(width 0.1)
				(type default)
			)
			(layer "F.Fab")
		)
		(fp_line
			(start -0.674878 -1.100074)
			(end -0.674878 1.100074)
			(stroke
				(width 0.1)
				(type default)
			)
			(layer "F.Fab")
		)
		(fp_line
			(start 0.674878 -1.100074)
			(end -0.674878 -1.100074)
			(stroke
				(width 0.1)
				(type default)
			)
			(layer "F.Fab")
		)
		(fp_poly
			(pts
				(xy -2.4384 -1.030986) (xy -2.4384 -0.268986) (xy -1.6764 -0.649986)
			)
			(stroke
				(width 0)
				(type default)
			)
			(fill yes)
			(layer "F.Fab")
		)
		(pad "1" smd rect
			(at -0.94996 -0.649986 180)
			(size 0.7112 0.9144)
			(layers "F.Cu" "F.Mask" "F.Paste")
			(net "GND")
		)
		(pad "2" smd rect
			(at -0.94996 0.649986 180)
			(size 0.7112 0.9144)
			(layers "F.Cu" "F.Mask" "F.Paste")
			(net "P1V5_BAT_IN")
		)
		(pad "3" smd rect
			(at 0.94996 0.649986 180)
			(size 0.7112 0.9144)
			(layers "F.Cu" "F.Mask" "F.Paste")
			(net "P1V5_BAT_OUT")
		)
		(pad "4" smd rect
			(at 0.94996 -0.649986 180)
			(size 0.7112 0.9144)
			(layers "F.Cu" "F.Mask" "F.Paste")
			(net "BAT_LDO_EN")
		)
	)
	(footprint ""
		(layer "F.Cu")
		(at 425.05884 -378.95403 -90)
		(property "Reference" "C842"
			(at 0 0 270)
			(layer "F.SilkS")
			(hide yes)
			(effects
				(font
					(size 1.27 1.27)
				)
			)
		)
		(property "Value" ""
			(at 0 0 270)
			(layer "F.Fab")
			(effects
				(font
					(size 1.27 1.27)
				)
			)
		)
		(duplicate_pad_numbers_are_jumpers no)
		(fp_line
			(start -0.299974 0.150114)
			(end -0.299974 -0.150114)
			(stroke
				(width 0.1)
				(type default)
			)
			(layer "F.Fab")
		)
		(fp_line
			(start 0.299974 0.150114)
			(end -0.299974 0.150114)
			(stroke
				(width 0.1)
				(type default)
			)
			(layer "F.Fab")
		)
		(fp_line
			(start -0.299974 -0.150114)
			(end 0.299974 -0.150114)
			(stroke
				(width 0.1)
				(type default)
			)
			(layer "F.Fab")
		)
		(fp_line
			(start 0.299974 -0.150114)
			(end 0.299974 0.150114)
			(stroke
				(width 0.1)
				(type default)
			)
			(layer "F.Fab")
		)
		(pad "1" smd rect
			(at -0.2667 0 270)
			(size 0.3048 0.381)
			(layers "F.Cu" "F.Mask" "F.Paste")
			(net "P5E_CPU0_P2_TX_C_DN<13>")
		)
		(pad "2" smd rect
			(at 0.2667 0 270)
			(size 0.3048 0.381)
			(layers "F.Cu" "F.Mask" "F.Paste")
			(net "P5E_CPU0_P2_TX_DN<13>")
		)
	)
	(footprint ""
		(layer "F.Cu")
		(at 145.669 -115.443 180)
		(property "Reference" "R8121"
			(at 0 0 180)
			(layer "F.SilkS")
			(hide yes)
			(effects
				(font
					(size 1.27 1.27)
				)
			)
		)
		(property "Value" ""
			(at 0 0 180)
			(layer "F.Fab")
			(effects
				(font
					(size 1.27 1.27)
				)
			)
		)
		(duplicate_pad_numbers_are_jumpers no)
		(fp_line
			(start 0.7874 0.4064)
			(end -0.7874 0.4064)
			(stroke
				(width 0.1524)
				(type default)
			)
			(layer "F.SilkS")
		)
		(fp_line
			(start 0.7874 -0.4064)
			(end 0.7874 0.4064)
			(stroke
				(width 0.1524)
				(type default)
			)
			(layer "F.SilkS")
		)
		(fp_line
			(start -0.7874 0.4064)
			(end -0.7874 -0.4064)
			(stroke
				(width 0.1524)
				(type default)
			)
			(layer "F.SilkS")
		)
		(fp_line
			(start -0.7874 -0.4064)
			(end 0.7874 -0.4064)
			(stroke
				(width 0.1524)
				(type default)
			)
			(layer "F.SilkS")
		)
		(fp_line
			(start 0.67945 0.3048)
			(end 0.120396 0.3048)
			(stroke
				(width 0.1)
				(type default)
			)
			(layer "F.Fab")
		)
		(fp_line
			(start 0.67945 -0.3048)
			(end 0.67945 0.3048)
			(stroke
				(width 0.1)
				(type default)
			)
			(layer "F.Fab")
		)
		(fp_line
			(start 0.12065 -0.2794)
			(end 0.12065 -0.3048)
			(stroke
				(width 0.1)
				(type default)
			)
			(layer "F.Fab")
		)
		(fp_line
			(start 0.12065 -0.3048)
			(end 0.67945 -0.3048)
			(stroke
				(width 0.1)
				(type default)
			)
			(layer "F.Fab")
		)
		(fp_line
			(start 0.120396 0.3048)
			(end 0.120396 0.2794)
			(stroke
				(width 0.1)
				(type default)
			)
			(layer "F.Fab")
		)
		(fp_line
			(start 0.120396 0.2794)
			(end -0.12065 0.2794)
			(stroke
				(width 0.1)
				(type default)
			)
			(layer "F.Fab")
		)
		(fp_line
			(start -0.12065 0.3048)
			(end -0.67945 0.3048)
			(stroke
				(width 0.1)
				(type default)
			)
			(layer "F.Fab")
		)
		(fp_line
			(start -0.12065 0.2794)
			(end -0.12065 0.3048)
			(stroke
				(width 0.1)
				(type default)
			)
			(layer "F.Fab")
		)
		(fp_line
			(start -0.12065 -0.2794)
			(end 0.12065 -0.2794)
			(stroke
				(width 0.1)
				(type default)
			)
			(layer "F.Fab")
		)
		(fp_line
			(start -0.12065 -0.305054)
			(end -0.12065 -0.2794)
			(stroke
				(width 0.1)
				(type default)
			)
			(layer "F.Fab")
		)
		(fp_line
			(start -0.67945 0.3048)
			(end -0.67945 -0.305054)
			(stroke
				(width 0.1)
				(type default)
			)
			(layer "F.Fab")
		)
		(fp_line
			(start -0.67945 -0.305054)
			(end -0.12065 -0.305054)
			(stroke
				(width 0.1)
				(type default)
			)
			(layer "F.Fab")
		)
		(pad "1" smd circle
			(at -0.40005 0 180)
			(size 0 0)
			(layers "F.Cu" "F.Mask" "F.Paste")
			(net "P12V_AUX")
		)
		(pad "2" smd circle
			(at 0.40005 0 180)
			(size 0 0)
			(layers "F.Cu" "F.Mask" "F.Paste")
			(net "P12V_AUX_UV_TRIGGER")
		)
	)
	(footprint ""
		(layer "F.Cu")
		(at 344.3605 -15.979394 90)
		(property "Reference" "R1207"
			(at 0 0 90)
			(layer "F.SilkS")
			(hide yes)
			(effects
				(font
					(size 1.27 1.27)
				)
			)
		)
		(property "Value" ""
			(at 0 0 90)
			(layer "F.Fab")
			(effects
				(font
					(size 1.27 1.27)
				)
			)
		)
		(duplicate_pad_numbers_are_jumpers no)
		(fp_line
			(start 0.7874 -0.4064)
			(end 0.7874 0.4064)
			(stroke
				(width 0.1524)
				(type default)
			)
			(layer "F.SilkS")
		)
		(fp_line
			(start -0.7874 -0.4064)
			(end 0.7874 -0.4064)
			(stroke
				(width 0.1524)
				(type default)
			)
			(layer "F.SilkS")
		)
		(fp_line
			(start 0.7874 0.4064)
			(end -0.7874 0.4064)
			(stroke
				(width 0.1524)
				(type default)
			)
			(layer "F.SilkS")
		)
		(fp_line
			(start -0.7874 0.4064)
			(end -0.7874 -0.4064)
			(stroke
				(width 0.1524)
				(type default)
			)
			(layer "F.SilkS")
		)
		(fp_line
			(start -0.12065 -0.305054)
			(end -0.12065 -0.2794)
			(stroke
				(width 0.1)
				(type default)
			)
			(layer "F.Fab")
		)
		(fp_line
			(start -0.67945 -0.305054)
			(end -0.12065 -0.305054)
			(stroke
				(width 0.1)
				(type default)
			)
			(layer "F.Fab")
		)
		(fp_line
			(start 0.67945 -0.3048)
			(end 0.67945 0.3048)
			(stroke
				(width 0.1)
				(type default)
			)
			(layer "F.Fab")
		)
		(fp_line
			(start 0.12065 -0.3048)
			(end 0.67945 -0.3048)
			(stroke
				(width 0.1)
				(type default)
			)
			(layer "F.Fab")
		)
		(fp_line
			(start 0.12065 -0.2794)
			(end 0.12065 -0.3048)
			(stroke
				(width 0.1)
				(type default)
			)
			(layer "F.Fab")
		)
		(fp_line
			(start -0.12065 -0.2794)
			(end 0.12065 -0.2794)
			(stroke
				(width 0.1)
				(type default)
			)
			(layer "F.Fab")
		)
		(fp_line
			(start 0.120396 0.2794)
			(end -0.12065 0.2794)
			(stroke
				(width 0.1)
				(type default)
			)
			(layer "F.Fab")
		)
		(fp_line
			(start -0.12065 0.2794)
			(end -0.12065 0.3048)
			(stroke
				(width 0.1)
				(type default)
			)
			(layer "F.Fab")
		)
		(fp_line
			(start 0.67945 0.3048)
			(end 0.120396 0.3048)
			(stroke
				(width 0.1)
				(type default)
			)
			(layer "F.Fab")
		)
		(fp_line
			(start 0.120396 0.3048)
			(end 0.120396 0.2794)
			(stroke
				(width 0.1)
				(type default)
			)
			(layer "F.Fab")
		)
		(fp_line
			(start -0.12065 0.3048)
			(end -0.67945 0.3048)
			(stroke
				(width 0.1)
				(type default)
			)
			(layer "F.Fab")
		)
		(fp_line
			(start -0.67945 0.3048)
			(end -0.67945 -0.305054)
			(stroke
				(width 0.1)
				(type default)
			)
			(layer "F.Fab")
		)
		(pad "1" smd circle
			(at -0.40005 0 90)
			(size 0 0)
			(layers "F.Cu" "F.Mask" "F.Paste")
			(net "P5V_STBY_PWR_LED")
		)
		(pad "2" smd circle
			(at 0.40005 0 90)
			(size 0 0)
			(layers "F.Cu" "F.Mask" "F.Paste")
			(net "P5V_AUX")
		)
	)
	(footprint ""
		(layer "F.Cu")
		(at 304.419 -359.283 180)
		(property "Reference" "C8072"
			(at 0 0 180)
			(layer "F.SilkS")
			(hide yes)
			(effects
				(font
					(size 1.27 1.27)
				)
			)
		)
		(property "Value" ""
			(at 0 0 180)
			(layer "F.Fab")
			(effects
				(font
					(size 1.27 1.27)
				)
			)
		)
		(duplicate_pad_numbers_are_jumpers no)
		(fp_line
			(start 0.7874 0.4064)
			(end -0.7874 0.4064)
			(stroke
				(width 0.1524)
				(type default)
			)
			(layer "F.SilkS")
		)
		(fp_line
			(start 0.7874 -0.4064)
			(end 0.7874 0.4064)
			(stroke
				(width 0.1524)
				(type default)
			)
			(layer "F.SilkS")
		)
		(fp_line
			(start -0.7874 0.4064)
			(end -0.7874 -0.4064)
			(stroke
				(width 0.1524)
				(type default)
			)
			(layer "F.SilkS")
		)
		(fp_line
			(start -0.7874 -0.4064)
			(end 0.7874 -0.4064)
			(stroke
				(width 0.1524)
				(type default)
			)
			(layer "F.SilkS")
		)
		(fp_line
			(start 0.67945 0.3048)
			(end 0.120396 0.3048)
			(stroke
				(width 0.1)
				(type default)
			)
			(layer "F.Fab")
		)
		(fp_line
			(start 0.67945 -0.3048)
			(end 0.67945 0.3048)
			(stroke
				(width 0.1)
				(type default)
			)
			(layer "F.Fab")
		)
		(fp_line
			(start 0.12065 -0.2794)
			(end 0.12065 -0.3048)
			(stroke
				(width 0.1)
				(type default)
			)
			(layer "F.Fab")
		)
		(fp_line
			(start 0.12065 -0.3048)
			(end 0.67945 -0.3048)
			(stroke
				(width 0.1)
				(type default)
			)
			(layer "F.Fab")
		)
		(fp_line
			(start 0.120396 0.3048)
			(end 0.120396 0.2794)
			(stroke
				(width 0.1)
				(type default)
			)
			(layer "F.Fab")
		)
		(fp_line
			(start 0.120396 0.2794)
			(end -0.12065 0.2794)
			(stroke
				(width 0.1)
				(type default)
			)
			(layer "F.Fab")
		)
		(fp_line
			(start -0.12065 0.3048)
			(end -0.67945 0.3048)
			(stroke
				(width 0.1)
				(type default)
			)
			(layer "F.Fab")
		)
		(fp_line
			(start -0.12065 0.2794)
			(end -0.12065 0.3048)
			(stroke
				(width 0.1)
				(type default)
			)
			(layer "F.Fab")
		)
		(fp_line
			(start -0.12065 -0.2794)
			(end 0.12065 -0.2794)
			(stroke
				(width 0.1)
				(type default)
			)
			(layer "F.Fab")
		)
		(fp_line
			(start -0.12065 -0.305054)
			(end -0.12065 -0.2794)
			(stroke
				(width 0.1)
				(type default)
			)
			(layer "F.Fab")
		)
		(fp_line
			(start -0.67945 0.3048)
			(end -0.67945 -0.305054)
			(stroke
				(width 0.1)
				(type default)
			)
			(layer "F.Fab")
		)
		(fp_line
			(start -0.67945 -0.305054)
			(end -0.12065 -0.305054)
			(stroke
				(width 0.1)
				(type default)
			)
			(layer "F.Fab")
		)
		(pad "1" smd circle
			(at -0.40005 0 180)
			(size 0 0)
			(layers "F.Cu" "F.Mask" "F.Paste")
			(net "PWRGD_PVDDIO_P0_R")
		)
		(pad "2" smd circle
			(at 0.40005 0 180)
			(size 0 0)
			(layers "F.Cu" "F.Mask" "F.Paste")
			(net "GND")
		)
	)
)
